#ISCELL
  mstr_misc dns *
  *
#ISCELL
  pure_quanta quanta_title_block_c *
  *
#ISCELL
  pure_quanta_power universal_gnd *
  page176_i1
#ISCELL
  pure_quanta_power vcc_core *
  page176_i106
#ISCELL
  pure_quanta_power universal_gnd *
  page176_i107
#CELL
  pure_quanta q_cap *
  page176_i108
#CELL
  pure_quanta q_cap *
  page176_i109
#CELL
  pure_quanta q_cap *
  page176_i111
#CELL
  pure_quanta q_res *
  page176_i112
#CELL
  pure_quanta q_res *
  page176_i124
#ISCELL
  pure_quanta_power universal_gnd *
  page176_i125
#ISCELL
  pure_quanta_power vcc_core *
  page176_i126
#CELL
  pure_quanta q_cap *
  page176_i127
#CELL
  pure_quanta q_cap *
  page176_i128
#ISCELL
  pure_quanta_power universal_gnd *
  page176_i13
#CELL
  pure_quanta q_inductor4p_14 *
  page176_i137
#CELL
  pure_quanta q_inductor4p_14 *
  page176_i138
#CELL
  pure_quanta q_cap *
  page176_i139
#CELL
  pure_quanta q_res *
  page176_i14
#CELL
  pure_quanta q_cap *
  page176_i140
#CELL
  pure_quanta q_cap *
  page176_i141
#CELL
  pure_quanta q_res *
  page176_i142
#CELL
  pure_quanta q_cap *
  page176_i143
#CELL
  pure_quanta q_res *
  page176_i144
#ISCELL
  standard offpage *
  page176_i145
#ISCELL
  standard offpage *
  page176_i146
#ISCELL
  standard offpage *
  page176_i147
#CELL
  pure_quanta q_capp *
  page176_i148
#ISCELL
  pure_quanta_power universal_gnd *
  page176_i149
#ISCELL
  standard offpage *
  page176_i15
#CELL
  pure_quanta q_capp *
  page176_i150
#CELL
  pure_quanta q_capp *
  page176_i151
#ISCELL
  pure_quanta_power vcc_core *
  page176_i152
#CELL
  pure_quanta q_capp *
  page176_i153
#CELL
  pure_quanta q_cap *
  page176_i154
#CELL
  pure_quanta q_cap *
  page176_i155
#CELL
  pure_quanta q_cap *
  page176_i156
#ISCELL
  pure_quanta_power universal_gnd *
  page176_i157
#ISCELL
  pure_quanta_power universal_gnd *
  page176_i158
#CELL
  pure_quanta q_res *
  page176_i159
#ISCELL
  standard offpage *
  page176_i16
#CELL
  pure_quanta q_cap *
  page176_i160
#CELL
  pure_quanta q_cap *
  page176_i162
#ISCELL
  pure_quanta_power universal_gnd *
  page176_i163
#ISCELL
  pure_quanta_power universal_gnd *
  page176_i164
#CELL
  pure_quanta q_res *
  page176_i165
#CELL
  pure_quanta q_cap *
  page176_i166
#CELL
  pure_quanta q_capp *
  page176_i168
#ISCELL
  standard offpage *
  page176_i169
#CELL
  pure_quanta q_cap *
  page176_i170
#CELL
  pure_quanta q_res *
  page176_i171
#ISCELL
  pure_quanta_power universal_gnd *
  page176_i172
#CELL
  pure_quanta q_cap *
  page176_i173
#CELL
  pure_quanta q_res *
  page176_i174
#ISCELL
  pure_quanta_power universal_gnd *
  page176_i175
#ISCELL
  standard offpage *
  page176_i176
#ISCELL
  pure_quanta_power vcc_core *
  page176_i182
#ISCELL
  pure_quanta_power vcc_core *
  page176_i183
#CELL
  pure_quanta q_res *
  page176_i184
#ISCELL
  pure_quanta_power vcc_core *
  page176_i185
#ISCELL
  pure_quanta_power vcc_core *
  page176_i186
#CELL
  pure_quanta q_res *
  page176_i187
#CELL
  pure_quanta q_res *
  page176_i188
#ISCELL
  pure_quanta_power universal_gnd *
  page176_i19
#CELL
  pure_quanta q_res *
  page176_i2
#CELL
  pure_quanta isl99390frztr5935 *
  page176_i21
#CELL
  pure_quanta q_cap *
  page176_i23
#CELL
  pure_quanta q_cap *
  page176_i24
#ISCELL
  pure_quanta_power universal_gnd *
  page176_i25
#ISCELL
  pure_quanta_power universal_gnd *
  page176_i26
#ISCELL
  standard offpage *
  page176_i27
#ISCELL
  standard offpage *
  page176_i28
#ISCELL
  standard offpage *
  page176_i3
#ISCELL
  pure_quanta_power universal_gnd *
  page176_i4
#CELL
  pure_quanta q_cap *
  page176_i41
#CELL
  pure_quanta q_cap *
  page176_i46
#CELL
  pure_quanta q_cap *
  page176_i47
#ISCELL
  pure_quanta_power universal_gnd *
  page176_i48
#ISCELL
  pure_quanta_power vcc_core *
  page176_i49
#ISCELL
  standard offpage *
  page176_i5
#ISCELL
  standard offpage *
  page176_i6
#ISCELL
  pure_quanta_power universal_gnd *
  page176_i64
#CELL
  pure_quanta q_cap *
  page176_i65
#CELL
  pure_quanta q_cap *
  page176_i66
#CELL
  pure_quanta q_cap *
  page176_i67
#ISCELL
  pure_quanta_power vcc_core *
  page176_i68
#ISCELL
  pure_quanta_power vcc_core *
  page176_i73
#CELL
  pure_quanta q_capp *
  page176_i74
#CELL
  pure_quanta q_inductor *
  page176_i75
#CELL
  pure_quanta q_capp *
  page176_i76
#CELL
  pure_quanta isl99390frztr5935 *
  page176_i87
